# T6G (Grand Teton) — schematic netlist excerpt (pin names and nets, part order shuffled) for the footprints in the layout excerpt that follows; sources: Cadence DE-HDL packaged netlist, KiCad conversion of 04192023_DAF0TMB3IC0_F0TG_MB_C_brd_V02_OCP.brd

X8009  TP_TDR_4P_FTS  TP_TDR_4P_DIP EMPTY  pkg TH  page 260
  S1  = TDR_DIFF_85_IN2_DN
  P1  = T1_GND
  P2  = T1_GND
  S2  = TDR_DIFF_85_IN2_DP

R1620  Q_RES  33 5% CHIP  pkg 0402LF  page 172 : A = HDT_HDR_TRST_N ; B = HDT_HDR_TRST_N_R

(kicad_pcb
	(version 20260206)
	(generator "pcbnew")
	(generator_version "10.0")
	(general
		(thickness 1.6)
		(legacy_teardrops no)
	)
	(paper "A4")
	(title_block
		(title "04192023_DAF0TMB3IC0_F0TG_MB_C_brd_V02_OCP.brd")
		(comment 1 "Grand Teton / footprints 3425-3426 of 8354")
	)
	(layers
		(0 "F.Cu" signal "TOP")
		(4 "In1.Cu" signal "GND")
		(6 "In2.Cu" signal "IN1")
		(8 "In3.Cu" signal "GND1")
		(10 "In4.Cu" signal "IN2")
		(12 "In5.Cu" signal "GND2")
		(14 "In6.Cu" signal "IN3")
		(16 "In7.Cu" signal "GND3")
		(18 "In8.Cu" signal "VCC")
		(20 "In9.Cu" signal "VCC1")
		(22 "In10.Cu" signal "GND4")
		(24 "In11.Cu" signal "IN4")
		(26 "In12.Cu" signal "GND5")
		(28 "In13.Cu" signal "IN5")
		(30 "In14.Cu" signal "GND6")
		(32 "In15.Cu" signal "IN6")
		(34 "In16.Cu" signal "GND7")
		(2 "B.Cu" signal "BOTTOM")
		(9 "F.Adhes" user "F.Adhesive")
		(11 "B.Adhes" user "B.Adhesive")
		(13 "F.Paste" user "Package Geometry/Pastemask Top")
		(15 "B.Paste" user "Package Geometry/Pastemask Bottom")
		(5 "F.SilkS" user "Ref Des/Silkscreen Top")
		(7 "B.SilkS" user "Ref Des/Silkscreen Bottom")
		(1 "F.Mask" user "Board Geometry/Soldermask Top")
		(3 "B.Mask" user "Board Geometry/Soldermask Bottom")
		(17 "Dwgs.User" user "User.Drawings")
		(19 "Cmts.User" user "User.Comments")
		(21 "Eco1.User" user "User.Eco1")
		(23 "Eco2.User" user "User.Eco2")
		(25 "Edge.Cuts" user "Board Geometry/Outline")
		(27 "Margin" user)
		(31 "F.CrtYd" user "Package Geometry/Place Bound Top")
		(29 "B.CrtYd" user "Package Geometry/Place Bound Bottom")
		(35 "F.Fab" user "Ref Des/Assembly Top")
		(33 "B.Fab" user "Ref Des/Assembly Bottom")
	)
	(footprint ""
		(layer "F.Cu")
		(at 501.233948 7.574534 -90)
		(property "Reference" "X8009"
			(at -1.815338 4.793488 0)
			(unlocked yes)
			(layer "F.SilkS")
			(effects
				(font
					(size 0.7874 0.5842)
					(thickness 0.1524)
				)
				(justify left)
			)
		)
		(property "Value" ""
			(at 0 0 270)
			(layer "F.Fab")
			(effects
				(font
					(size 1.27 1.27)
				)
			)
		)
		(property "Device Type" "TP_TDR_4P_FTS_TH-TP_TDR_4P_DIP,EMPTY,TP15"
			(at 1.30175 1.27 0)
			(unlocked yes)
			(layer "F.Fab")
			(hide yes)
			(effects
				(font
					(size 0.635 0.4064)
					(thickness 0.1524)
				)
			)
		)
		(property "User Part Number" "N_A"
			(at 1.30175 1.27 0)
			(unlocked yes)
			(layer "Cmts.User")
			(hide yes)
			(effects
				(font
					(size 0.635 0.4064)
					(thickness 0.1524)
				)
			)
		)
		(duplicate_pad_numbers_are_jumpers no)
		(fp_line
			(start 0 3.81)
			(end 2.54 3.81)
			(stroke
				(width 0.1524)
				(type default)
			)
			(layer "F.SilkS")
		)
		(fp_line
			(start 2.54 3.81)
			(end 2.54 3.6703)
			(stroke
				(width 0.1524)
				(type default)
			)
			(layer "F.SilkS")
		)
		(fp_line
			(start 0 3.175)
			(end 0 3.81)
			(stroke
				(width 0.1524)
				(type default)
			)
			(layer "F.SilkS")
		)
		(fp_line
			(start 2.54 1.4097)
			(end 2.54 1.1303)
			(stroke
				(width 0.1524)
				(type default)
			)
			(layer "F.SilkS")
		)
		(fp_line
			(start 0 0.635)
			(end 0 1.905)
			(stroke
				(width 0.1524)
				(type default)
			)
			(layer "F.SilkS")
		)
		(fp_line
			(start 2.54 -1.1303)
			(end 2.54 -1.27)
			(stroke
				(width 0.1524)
				(type default)
			)
			(layer "F.SilkS")
		)
		(fp_line
			(start 0 -1.27)
			(end 0 -0.635)
			(stroke
				(width 0.1524)
				(type default)
			)
			(layer "F.SilkS")
		)
		(fp_line
			(start 2.54 -1.27)
			(end 0 -1.27)
			(stroke
				(width 0.1524)
				(type default)
			)
			(layer "F.SilkS")
		)
		(fp_poly
			(pts
				(xy -2.285746 -0.762) (xy -0.761746 0) (xy -2.285746 0.762)
			)
			(stroke
				(width 0)
				(type default)
			)
			(fill yes)
			(layer "F.SilkS")
		)
		(fp_line
			(start 0 3.81)
			(end 2.54 3.81)
			(stroke
				(width 0.1)
				(type default)
			)
			(layer "F.Fab")
		)
		(fp_line
			(start 2.54 3.81)
			(end 2.54 -1.27)
			(stroke
				(width 0.1)
				(type default)
			)
			(layer "F.Fab")
		)
		(fp_line
			(start 0 -1.27)
			(end 0 3.81)
			(stroke
				(width 0.1)
				(type default)
			)
			(layer "F.Fab")
		)
		(fp_line
			(start 2.54 -1.27)
			(end 0 -1.27)
			(stroke
				(width 0.1)
				(type default)
			)
			(layer "F.Fab")
		)
		(fp_poly
			(pts
				(xy -0.761746 0) (xy -2.285746 -0.762) (xy -2.285746 0.762)
			)
			(stroke
				(width 0)
				(type default)
			)
			(fill yes)
			(layer "F.Fab")
		)
		(pad "1" thru_hole circle
			(at 0 0 270)
			(size 1.0033 1.0033)
			(drill 0.249936)
			(layers "*.Cu" "*.Mask")
			(remove_unused_layers no)
			(net "TDR_DIFF_85_IN2_DN")
			(clearance 0.10795)
			(thermal_gap 0.10795)
			(padstack
				(mode front_inner_back)
				(layer "Inner"
					(shape circle)
					(size 0.8001 0.8001)
					(clearance 0.1524)
				)
				(layer "B.Cu"
					(shape circle)
					(size 1.0033 1.0033)
					(clearance 0.10795)
				)
			)
		)
		(pad "2" thru_hole circle
			(at 2.54 0 270)
			(size 1.9939 1.9939)
			(drill 0.249936)
			(layers "*.Cu" "*.Mask")
			(remove_unused_layers no)
			(net "T1_GND")
			(clearance 0.10795)
			(thermal_gap 0.10795)
			(padstack
				(mode front_inner_back)
				(layer "Inner"
					(shape circle)
					(size 0.8001 0.8001)
					(clearance 0.1524)
				)
				(layer "B.Cu"
					(shape circle)
					(size 1.9939 1.9939)
					(clearance 0.10795)
				)
			)
		)
		(pad "3" thru_hole circle
			(at 2.54 2.54 270)
			(size 1.9939 1.9939)
			(drill 0.249936)
			(layers "*.Cu" "*.Mask")
			(remove_unused_layers no)
			(net "T1_GND")
			(clearance 0.10795)
			(thermal_gap 0.10795)
			(padstack
				(mode front_inner_back)
				(layer "Inner"
					(shape circle)
					(size 0.8001 0.8001)
					(clearance 0.1524)
				)
				(layer "B.Cu"
					(shape circle)
					(size 1.9939 1.9939)
					(clearance 0.10795)
				)
			)
		)
		(pad "4" thru_hole circle
			(at 0 2.54 270)
			(size 1.0033 1.0033)
			(drill 0.249936)
			(layers "*.Cu" "*.Mask")
			(remove_unused_layers no)
			(net "TDR_DIFF_85_IN2_DP")
			(clearance 0.10795)
			(thermal_gap 0.10795)
			(padstack
				(mode front_inner_back)
				(layer "Inner"
					(shape circle)
					(size 0.8001 0.8001)
					(clearance 0.1524)
				)
				(layer "B.Cu"
					(shape circle)
					(size 1.0033 1.0033)
					(clearance 0.10795)
				)
			)
		)
	)
	(footprint ""
		(layer "F.Cu")
		(at 403.682962 -57.2135 180)
		(property "Reference" "R1620"
			(at 0 0 180)
			(layer "F.SilkS")
			(hide yes)
			(effects
				(font
					(size 1.27 1.27)
				)
			)
		)
		(property "Value" ""
			(at 0 0 180)
			(layer "F.Fab")
			(effects
				(font
					(size 1.27 1.27)
				)
			)
		)
		(duplicate_pad_numbers_are_jumpers no)
		(fp_line
			(start 0.7874 0.4064)
			(end -0.7874 0.4064)
			(stroke
				(width 0.1524)
				(type default)
			)
			(layer "F.SilkS")
		)
		(fp_line
			(start 0.7874 -0.4064)
			(end 0.7874 0.4064)
			(stroke
				(width 0.1524)
				(type default)
			)
			(layer "F.SilkS")
		)
		(fp_line
			(start -0.7874 0.4064)
			(end -0.7874 -0.4064)
			(stroke
				(width 0.1524)
				(type default)
			)
			(layer "F.SilkS")
		)
		(fp_line
			(start -0.7874 -0.4064)
			(end 0.7874 -0.4064)
			(stroke
				(width 0.1524)
				(type default)
			)
			(layer "F.SilkS")
		)
		(fp_line
			(start 0.67945 0.3048)
			(end 0.120396 0.3048)
			(stroke
				(width 0.1)
				(type default)
			)
			(layer "F.Fab")
		)
		(fp_line
			(start 0.67945 -0.3048)
			(end 0.67945 0.3048)
			(stroke
				(width 0.1)
				(type default)
			)
			(layer "F.Fab")
		)
		(fp_line
			(start 0.12065 -0.2794)
			(end 0.12065 -0.3048)
			(stroke
				(width 0.1)
				(type default)
			)
			(layer "F.Fab")
		)
		(fp_line
			(start 0.12065 -0.3048)
			(end 0.67945 -0.3048)
			(stroke
				(width 0.1)
				(type default)
			)
			(layer "F.Fab")
		)
		(fp_line
			(start 0.120396 0.3048)
			(end 0.120396 0.2794)
			(stroke
				(width 0.1)
				(type default)
			)
			(layer "F.Fab")
		)
		(fp_line
			(start 0.120396 0.2794)
			(end -0.12065 0.2794)
			(stroke
				(width 0.1)
				(type default)
			)
			(layer "F.Fab")
		)
		(fp_line
			(start -0.12065 0.3048)
			(end -0.67945 0.3048)
			(stroke
				(width 0.1)
				(type default)
			)
			(layer "F.Fab")
		)
		(fp_line
			(start -0.12065 0.2794)
			(end -0.12065 0.3048)
			(stroke
				(width 0.1)
				(type default)
			)
			(layer "F.Fab")
		)
		(fp_line
			(start -0.12065 -0.2794)
			(end 0.12065 -0.2794)
			(stroke
				(width 0.1)
				(type default)
			)
			(layer "F.Fab")
		)
		(fp_line
			(start -0.12065 -0.305054)
			(end -0.12065 -0.2794)
			(stroke
				(width 0.1)
				(type default)
			)
			(layer "F.Fab")
		)
		(fp_line
			(start -0.67945 0.3048)
			(end -0.67945 -0.305054)
			(stroke
				(width 0.1)
				(type default)
			)
			(layer "F.Fab")
		)
		(fp_line
			(start -0.67945 -0.305054)
			(end -0.12065 -0.305054)
			(stroke
				(width 0.1)
				(type default)
			)
			(layer "F.Fab")
		)
		(pad "1" smd circle
			(at -0.40005 0 180)
			(size 0 0)
			(layers "F.Cu" "F.Mask" "F.Paste")
			(net "HDT_HDR_TRST_N")
		)
		(pad "2" smd circle
			(at 0.40005 0 180)
			(size 0 0)
			(layers "F.Cu" "F.Mask" "F.Paste")
			(net "HDT_HDR_TRST_N_R")
		)
	)
)
